# T6G (Grand Teton) — schematic netlist excerpt (pin names and nets, part order shuffled) for the footprints in the layout excerpt that follows; sources: Cadence DE-HDL packaged netlist, KiCad conversion of 04192023_DAF0TMB3IC0_F0TG_MB_C_brd_V02_OCP.brd

J17  SCONN288_DDR506112002KQ  IO  pkg DDR288S_1-1VXC  page 88
  VIN_BULK0  = P12V_MEM_CPU0
  RFU0  = NC
  VIN_MGMT  = P3V3_AUX
  HSCL  = I3C_SPD_DDRC_CPU0_SCL
  HSDA  = I3C_SPD_DDRC_CPU0_SDA
  VSS0  = GND
  DQ0_A  = M_C_CPU0_SA_DQ<0>
  VSS1  = GND
  DQ1_A  = M_C_CPU0_SA_DQ<1>
  VSS2  = GND
  DQS0_A_T  = M_C_CPU0_SA_DQS_DP<0>
  DQS0_A_C  = M_C_CPU0_SA_DQS_DN<0>
  VSS3  = GND
  DQ4_A  = M_C_CPU0_SA_DQ<4>
  VSS4  = GND
  DQ5_A  = M_C_CPU0_SA_DQ<5>
  VSS5  = GND
  DQ8_A  = M_C_CPU0_SA_DQ<8>
  VSS6  = GND
  DQ9_A  = M_C_CPU0_SA_DQ<9>
  VSS7  = GND
  DQS1_A_T  = M_C_CPU0_SA_DQS_DP<1>
  DQS1_A_C  = M_C_CPU0_SA_DQS_DN<1>
  VSS8  = GND
  DQ12_A  = M_C_CPU0_SA_DQ<12>
  VSS9  = GND
  DQ13_A  = M_C_CPU0_SA_DQ<13>
  VSS10  = GND
  DQ16_A  = M_C_CPU0_SA_DQ<16>
  VSS11  = GND
  DQ17_A  = M_C_CPU0_SA_DQ<17>
  VSS12  = GND
  DQS2_A_T  = M_C_CPU0_SA_DQS_DP<2>
  DQS2_A_C  = M_C_CPU0_SA_DQS_DN<2>
  VSS13  = GND
  DQ20_A  = M_C_CPU0_SA_DQ<20>
  VSS14  = GND
  DQ21_A  = M_C_CPU0_SA_DQ<21>
  VSS15  = GND
  DQ24_A  = M_C_CPU0_SA_DQ<24>
  VSS16  = GND
  DQ25_A  = M_C_CPU0_SA_DQ<25>
  VSS17  = GND
  DQS3_A_T  = M_C_CPU0_SA_DQS_DP<3>
  DQS3_A_C  = M_C_CPU0_SA_DQS_DN<3>
  VSS18  = GND
  DQ28_A  = M_C_CPU0_SA_DQ<28>
  VSS19  = GND
  DQ29_A  = M_C_CPU0_SA_DQ<29>
  VSS20  = GND
  CB0_A  = M_C_CPU0_SA_CB<0>
  VSS21  = GND
  CB1_A  = M_C_CPU0_SA_CB<1>
  VSS22  = GND
  DQS4_A_T  = M_C_CPU0_SA_DQS_DP<4>
  DQS4_A_C  = M_C_CPU0_SA_DQS_DN<4>
  VSS23  = GND
  CB4_A  = M_C_CPU0_SA_CB<4>
  VSS24  = GND
  CB5_A  = M_C_CPU0_SA_CB<5>
  VSS25  = GND
  ALERT_N  = M_C_CPU0_ALERT_N
  VSS26  = GND
  CS0_A_N  = M_C_CPU0_SA_CS_N<0>
  VSS27  = GND
  CA0_A  = M_C_CPU0_SA_CA<0>
  VSS28  = GND
  CA2_A  = M_C_CPU0_SA_CA<2>
  VSS29  = GND
  CA4_A  = M_C_CPU0_SA_CA<4>
  VSS30  = GND
  CA6_A  = M_C_CPU0_SA_CA<6>
  VSS31  = GND
  PAR_A  = M_C_CPU0_SA_PAR
  VSS32  = GND
  CA0_B  = M_C_CPU0_SB_CA<0>
  VSS33  = GND
  CA2_B  = M_C_CPU0_SB_CA<2>
  VSS34  = GND
  CA4_B  = M_C_CPU0_SB_CA<4>
  VSS35  = GND
  CA6_B  = M_C_CPU0_SB_CA<6>
  VSS36  = GND
  CS0_B_N  = M_C_CPU0_SB_CS_N<0>
  VSS37  = GND
  \lbd||rsp_a_n\  = M_C_CPU0_SA_RSP<0>
  \lbs||rsp_b_n\  = M_C_CPU0_SB_RSP<0>
  VSS38  = GND
  CB4_B  = M_C_CPU0_SB_CB<4>
  VSS39  = GND
  CB5_B  = M_C_CPU0_SB_CB<5>
  VSS40  = GND
  \dqs9_b_t||tdqs9_b_t||dbi4_b_n\  = M_C_CPU0_SB_DQS_DP<9>
  \dqs9_b_c||tdqs9_b_c\  = M_C_CPU0_SB_DQS_DN<9>
  VSS41  = GND
  CB0_B  = M_C_CPU0_SB_CB<0>
  VSS42  = GND
  CB1_B  = M_C_CPU0_SB_CB<1>
  VSS43  = GND
  DQ0_B  = M_C_CPU0_SB_DQ<0>
  VSS44  = GND
  DQ1_B  = M_C_CPU0_SB_DQ<1>
  VSS45  = GND
  DQS0_B_T  = M_C_CPU0_SB_DQS_DP<0>
  DQS0_B_C  = M_C_CPU0_SB_DQS_DN<0>
  VSS46  = GND
  DQ4_B  = M_C_CPU0_SB_DQ<4>
  VSS47  = GND
  DQ5_B  = M_C_CPU0_SB_DQ<5>
  VSS48  = GND
  DQ8_B  = M_C_CPU0_SB_DQ<8>
  VSS49  = GND
  DQ9_B  = M_C_CPU0_SB_DQ<9>
  VSS50  = GND
  DQS1_B_T  = M_C_CPU0_SB_DQS_DP<1>
  DQS1_B_C  = M_C_CPU0_SB_DQS_DN<1>
  VSS51  = GND
  DQ12_B  = M_C_CPU0_SB_DQ<12>
  VSS52  = GND
  DQ13_B  = M_C_CPU0_SB_DQ<13>
  VSS53  = GND
  DQ16_B  = M_C_CPU0_SB_DQ<16>
  VSS54  = GND
  DQ17_B  = M_C_CPU0_SB_DQ<17>
  VSS55  = GND
  DQS2_B_T  = M_C_CPU0_SB_DQS_DP<2>
  DQS2_B_C  = M_C_CPU0_SB_DQS_DN<2>
  VSS56  = GND
  DQ20_B  = M_C_CPU0_SB_DQ<20>
  VSS57  = GND
  DQ21_B  = M_C_CPU0_SB_DQ<21>
  VSS58  = GND
  DQ24_B  = M_C_CPU0_SB_DQ<24>
  VSS59  = GND
  DQ25_B  = M_C_CPU0_SB_DQ<25>
  VSS60  = GND
  DQS3_B_T  = M_C_CPU0_SB_DQS_DP<3>
  DQS3_B_C  = M_C_CPU0_SB_DQS_DN<3>
  VSS61  = GND
  DQ28_B  = M_C_CPU0_SB_DQ<28>
  VSS62  = GND
  DQ29_B  = M_C_CPU0_SB_DQ<29>
  VSS63  = GND
  RFU1  = NC
  VIN_BULK1  = P12V_MEM_CPU0
  VIN_BULK2  = P12V_MEM_CPU0
  \pwr_good||fail_n\  = PWRGD_CHC_CPU0_DIMM
  HAS  = PD_CHC_CPU0_DIMM_SAA
  RFU2  = NC
  RFU3  = NC
  VSS64  = GND
  DQ2_A  = M_C_CPU0_SA_DQ<2>
  VSS65  = GND
  DQ3_A  = M_C_CPU0_SA_DQ<3>
  VSS66  = GND
  \dqs5_a_c||tdqs5_a_c||dqs5_a_t||tdqs5_a_t\  = M_C_CPU0_SA_DQS_DN<5>
  \dqs5_a_t||tdqs5_a_t\  = M_C_CPU0_SA_DQS_DP<5>
  VSS67  = GND
  DQ6_A  = M_C_CPU0_SA_DQ<6>
  VSS68  = GND
  DQ7_A  = M_C_CPU0_SA_DQ<7>
  VSS69  = GND
  DQ10_A  = M_C_CPU0_SA_DQ<10>
  VSS70  = GND
  DQ11_A  = M_C_CPU0_SA_DQ<11>
  VSS71  = GND
  \dqs6_a_c||tdqs6_a_c||dqs6_a_t||tdqs6_a_t\  = M_C_CPU0_SA_DQS_DN<6>
  \dqs6_a_t||tdqs6_a_t\  = M_C_CPU0_SA_DQS_DP<6>
  VSS72  = GND
  DQ14_A  = M_C_CPU0_SA_DQ<14>
  VSS73  = GND
  DQ15_A  = M_C_CPU0_SA_DQ<15>
  VSS74  = GND
  DQ18_A  = M_C_CPU0_SA_DQ<18>
  VSS75  = GND
  DQ19_A  = M_C_CPU0_SA_DQ<19>
  VSS76  = GND
  \dqs7_a_c||tdqs7_a_c\  = M_C_CPU0_SA_DQS_DN<7>
  \dqs7_a_t||tdqs7_a_t\  = M_C_CPU0_SA_DQS_DP<7>
  VSS77  = GND
  DQ22_A  = M_C_CPU0_SA_DQ<22>
  VSS78  = GND
  DQ23_A  = M_C_CPU0_SA_DQ<23>
  VSS79  = GND
  DQ26_A  = M_C_CPU0_SA_DQ<26>
  VSS80  = GND
  DQ27_A  = M_C_CPU0_SA_DQ<27>
  VSS81  = GND
  \dqs8_a_c||tdqs8_a_c\  = M_C_CPU0_SA_DQS_DN<8>
  \dqs8_a_t||tdqs8_a_t\  = M_C_CPU0_SA_DQS_DP<8>
  VSS82  = GND
  DQ30_A  = M_C_CPU0_SA_DQ<30>
  VSS83  = GND
  DQ31_A  = M_C_CPU0_SA_DQ<31>
  VSS84  = GND
  CB2_A  = M_C_CPU0_SA_CB<2>
  VSS85  = GND
  CB3_A  = M_C_CPU0_SA_CB<3>
  VSS86  = GND
  \dqs9_a_c||tdqs9_a_c\  = M_C_CPU0_SA_DQS_DN<9>
  \dqs9_a_t||tdqs9_a_t\  = M_C_CPU0_SA_DQS_DP<9>
  VSS87  = GND
  CB6_A  = M_C_CPU0_SA_CB<6>
  VSS88  = GND
  CB7_A  = M_C_CPU0_SA_CB<7>
  VSS89  = GND
  RESET_N  = M_C_CPU0_RESET_N
  VSS90  = GND
  CS1_A_N  = M_C_CPU0_SA_CS_N<1>
  VSS91  = GND
  CA1_A  = M_C_CPU0_SA_CA<1>
  VSS92  = GND
  CA3_A  = M_C_CPU0_SA_CA<3>
  VSS93  = GND
  CA5_A  = M_C_CPU0_SA_CA<5>
  VSS94  = GND
  CK_T  = M_C_CPU0_CLK_DP<0>
  CK_C  = M_C_CPU0_CLK_DN<0>
  VSS95  = GND
  RFU4  = NC
  CA1_B  = M_C_CPU0_SB_CA<1>
  VSS96  = GND
  CA3_B  = M_C_CPU0_SB_CA<3>
  VSS97  = GND
  CA5_B  = M_C_CPU0_SB_CA<5>
  VSS98  = GND
  PAR_B  = M_C_CPU0_SB_PAR
  VSS99  = GND
  CS1_B_N  = M_C_CPU0_SB_CS_N<1>
  VSS100  = GND
  RFU5  = NC
  RFU6  = NC
  VSS101  = GND
  CB6_B  = M_C_CPU0_SB_CB<6>
  VSS102  = GND
  CB7_B  = M_C_CPU0_SB_CB<7>
  VSS103  = GND
  DQS4_B_C  = M_C_CPU0_SB_DQS_DN<4>
  DQS4_B_T  = M_C_CPU0_SB_DQS_DP<4>
  VSS104  = GND
  CB2_B  = M_C_CPU0_SB_CB<2>
  VSS105  = GND
  CB3_B  = M_C_CPU0_SB_CB<3>
  VSS106  = GND
  DQ2_B  = M_C_CPU0_SB_DQ<2>
  VSS107  = GND
  DQ3_B  = M_C_CPU0_SB_DQ<3>
  VSS108  = GND
  \dqs5_b_c||tdqs5_b_c\  = M_C_CPU0_SB_DQS_DN<5>
  \dqs5_b_t||tdqs5_b_t\  = M_C_CPU0_SB_DQS_DP<5>
  VSS109  = GND
  DQ6_B  = M_C_CPU0_SB_DQ<6>
  VSS110  = GND
  DQ7_B  = M_C_CPU0_SB_DQ<7>
  VSS111  = GND
  DQ10_B  = M_C_CPU0_SB_DQ<10>
  VSS112  = GND
  DQ11_B  = M_C_CPU0_SB_DQ<11>
  VSS113  = GND
  \dqs6_b_c||tdqs6_b_c\  = M_C_CPU0_SB_DQS_DN<6>
  \dqs6_b_t||tdqs6_b_t\  = M_C_CPU0_SB_DQS_DP<6>
  VSS114  = GND
  DQ14_B  = M_C_CPU0_SB_DQ<14>
  VSS115  = GND
  DQ15_B  = M_C_CPU0_SB_DQ<15>
  VSS116  = GND
  DQ18_B  = M_C_CPU0_SB_DQ<18>
  VSS117  = GND
  DQ19_B  = M_C_CPU0_SB_DQ<19>
  VSS118  = GND
  \dqs7_b_c||tdqs7_b_c\  = M_C_CPU0_SB_DQS_DN<7>
  \dqs7_b_t||tdqs7_b_t\  = M_C_CPU0_SB_DQS_DP<7>
  VSS119  = GND
  DQ22_B  = M_C_CPU0_SB_DQ<22>
  VSS120  = GND
  DQ23_B  = M_C_CPU0_SB_DQ<23>
  VSS121  = GND
  DQ26_B  = M_C_CPU0_SB_DQ<26>
  VSS122  = GND
  DQ27_B  = M_C_CPU0_SB_DQ<27>
  VSS123  = GND
  \dqs8_b_c||tdqs8_b_c\  = M_C_CPU0_SB_DQS_DN<8>
  \dqs8_b_t||tdqs8_b_t\  = M_C_CPU0_SB_DQS_DP<8>
  VSS124  = GND
  DQ30_B  = M_C_CPU0_SB_DQ<30>
  VSS125  = GND
  DQ31_B  = M_C_CPU0_SB_DQ<31>
  VSS126  = GND
  G1  = GND
  G2  = GND
  G3  = GND

(kicad_pcb
	(version 20260206)
	(generator "pcbnew")
	(generator_version "10.0")
	(general
		(thickness 1.6)
		(legacy_teardrops no)
	)
	(paper "A4")
	(title_block
		(title "04192023_DAF0TMB3IC0_F0TG_MB_C_brd_V02_OCP.brd")
		(comment 1 "Grand Teton / footprint 4167 of 8354 (J17), pads 139-184 of 291")
	)
	(layers
		(0 "F.Cu" signal "TOP")
		(4 "In1.Cu" signal "GND")
		(6 "In2.Cu" signal "IN1")
		(8 "In3.Cu" signal "GND1")
		(10 "In4.Cu" signal "IN2")
		(12 "In5.Cu" signal "GND2")
		(14 "In6.Cu" signal "IN3")
		(16 "In7.Cu" signal "GND3")
		(18 "In8.Cu" signal "VCC")
		(20 "In9.Cu" signal "VCC1")
		(22 "In10.Cu" signal "GND4")
		(24 "In11.Cu" signal "IN4")
		(26 "In12.Cu" signal "GND5")
		(28 "In13.Cu" signal "IN5")
		(30 "In14.Cu" signal "GND6")
		(32 "In15.Cu" signal "IN6")
		(34 "In16.Cu" signal "GND7")
		(2 "B.Cu" signal "BOTTOM")
		(9 "F.Adhes" user "F.Adhesive")
		(11 "B.Adhes" user "B.Adhesive")
		(13 "F.Paste" user "Package Geometry/Pastemask Top")
		(15 "B.Paste" user "Package Geometry/Pastemask Bottom")
		(5 "F.SilkS" user "Ref Des/Silkscreen Top")
		(7 "B.SilkS" user "Ref Des/Silkscreen Bottom")
		(1 "F.Mask" user "Board Geometry/Soldermask Top")
		(3 "B.Mask" user "Board Geometry/Soldermask Bottom")
		(17 "Dwgs.User" user "User.Drawings")
		(19 "Cmts.User" user "User.Comments")
		(21 "Eco1.User" user "User.Eco1")
		(23 "Eco2.User" user "User.Eco2")
		(25 "Edge.Cuts" user "Board Geometry/Outline")
		(27 "Margin" user)
		(31 "F.CrtYd" user "Package Geometry/Place Bound Top")
		(29 "B.CrtYd" user "Package Geometry/Place Bound Bottom")
		(35 "F.Fab" user "Ref Des/Assembly Top")
		(33 "B.Fab" user "Ref Des/Assembly Bottom")
	)
	(footprint ""
		(layer "F.Cu")
		(at 290.230052 -255.560068 180)
		(property "Reference" "J17"
			(at -2.2098 -81.984088 0)
			(unlocked yes)
			(layer "F.SilkS")
			(effects
				(font
					(size 0.7874 0.5842)
					(thickness 0.1524)
				)
			)
		)
		(property "Value" ""
			(at 0 0 180)
			(layer "F.Fab")
			(effects
				(font
					(size 1.27 1.27)
				)
			)
		)
		(duplicate_pad_numbers_are_jumpers no)
		(pad "139" smd rect
			(at -2.050034 59.075066 90)
			(size 0.519938 1.4986)
			(layers "F.Cu" "F.Mask" "F.Paste")
			(net "GND")
		)
		(pad "140" smd rect
			(at -2.050034 59.92495 90)
			(size 0.519938 1.4986)
			(layers "F.Cu" "F.Mask" "F.Paste")
			(net "M_C_CPU0_SB_DQ<28>")
		)
		(pad "141" smd rect
			(at -2.050034 60.775088 90)
			(size 0.519938 1.4986)
			(layers "F.Cu" "F.Mask" "F.Paste")
			(net "GND")
		)
		(pad "142" smd rect
			(at -2.050034 61.624972 90)
			(size 0.519938 1.4986)
			(layers "F.Cu" "F.Mask" "F.Paste")
			(net "M_C_CPU0_SB_DQ<29>")
		)
		(pad "143" smd rect
			(at -2.050034 62.47511 90)
			(size 0.519938 1.4986)
			(layers "F.Cu" "F.Mask" "F.Paste")
			(net "GND")
		)
		(pad "144" smd rect
			(at -2.050034 63.324994 90)
			(size 0.519938 1.4986)
			(layers "F.Cu" "F.Mask" "F.Paste")
			(net "Net_2278")
		)
		(pad "145" smd rect
			(at 2.050034 -63.324994 90)
			(size 0.519938 1.4986)
			(layers "F.Cu" "F.Mask" "F.Paste")
			(net "P12V_MEM_CPU0")
		)
		(pad "146" smd rect
			(at 2.050034 -62.47511 90)
			(size 0.519938 1.4986)
			(layers "F.Cu" "F.Mask" "F.Paste")
			(net "P12V_MEM_CPU0")
		)
		(pad "147" smd rect
			(at 2.050034 -61.624972 90)
			(size 0.519938 1.4986)
			(layers "F.Cu" "F.Mask" "F.Paste")
			(net "PWRGD_CHC_CPU0_DIMM")
		)
		(pad "148" smd rect
			(at 2.050034 -60.775088 90)
			(size 0.519938 1.4986)
			(layers "F.Cu" "F.Mask" "F.Paste")
			(net "PD_CHC_CPU0_DIMM_SAA")
		)
		(pad "149" smd rect
			(at 2.050034 -59.92495 90)
			(size 0.519938 1.4986)
			(layers "F.Cu" "F.Mask" "F.Paste")
			(net "Net_2279")
		)
		(pad "150" smd rect
			(at 2.050034 -59.075066 90)
			(size 0.519938 1.4986)
			(layers "F.Cu" "F.Mask" "F.Paste")
			(net "Net_2280")
		)
		(pad "151" smd rect
			(at 2.050034 -58.224928 90)
			(size 0.519938 1.4986)
			(layers "F.Cu" "F.Mask" "F.Paste")
			(net "GND")
		)
		(pad "152" smd rect
			(at 2.050034 -57.375044 90)
			(size 0.519938 1.4986)
			(layers "F.Cu" "F.Mask" "F.Paste")
			(net "M_C_CPU0_SA_DQ<2>")
		)
		(pad "153" smd rect
			(at 2.050034 -56.524906 90)
			(size 0.519938 1.4986)
			(layers "F.Cu" "F.Mask" "F.Paste")
			(net "GND")
		)
		(pad "154" smd rect
			(at 2.050034 -55.675022 90)
			(size 0.519938 1.4986)
			(layers "F.Cu" "F.Mask" "F.Paste")
			(net "M_C_CPU0_SA_DQ<3>")
		)
		(pad "155" smd rect
			(at 2.050034 -54.824884 90)
			(size 0.519938 1.4986)
			(layers "F.Cu" "F.Mask" "F.Paste")
			(net "GND")
		)
		(pad "156" smd rect
			(at 2.050034 -53.975 90)
			(size 0.519938 1.4986)
			(layers "F.Cu" "F.Mask" "F.Paste")
			(net "M_C_CPU0_SA_DQS_DN<5>")
		)
		(pad "157" smd rect
			(at 2.050034 -53.125116 90)
			(size 0.519938 1.4986)
			(layers "F.Cu" "F.Mask" "F.Paste")
			(net "M_C_CPU0_SA_DQS_DP<5>")
		)
		(pad "158" smd rect
			(at 2.050034 -52.274978 90)
			(size 0.519938 1.4986)
			(layers "F.Cu" "F.Mask" "F.Paste")
			(net "GND")
		)
		(pad "159" smd rect
			(at 2.050034 -51.425094 90)
			(size 0.519938 1.4986)
			(layers "F.Cu" "F.Mask" "F.Paste")
			(net "M_C_CPU0_SA_DQ<6>")
		)
		(pad "160" smd rect
			(at 2.050034 -50.574956 90)
			(size 0.519938 1.4986)
			(layers "F.Cu" "F.Mask" "F.Paste")
			(net "GND")
		)
		(pad "161" smd rect
			(at 2.050034 -49.725072 90)
			(size 0.519938 1.4986)
			(layers "F.Cu" "F.Mask" "F.Paste")
			(net "M_C_CPU0_SA_DQ<7>")
		)
		(pad "162" smd rect
			(at 2.050034 -48.874934 90)
			(size 0.519938 1.4986)
			(layers "F.Cu" "F.Mask" "F.Paste")
			(net "GND")
		)
		(pad "163" smd rect
			(at 2.050034 -48.02505 90)
			(size 0.519938 1.4986)
			(layers "F.Cu" "F.Mask" "F.Paste")
			(net "M_C_CPU0_SA_DQ<10>")
		)
		(pad "164" smd rect
			(at 2.050034 -47.174912 90)
			(size 0.519938 1.4986)
			(layers "F.Cu" "F.Mask" "F.Paste")
			(net "GND")
		)
		(pad "165" smd rect
			(at 2.050034 -46.325028 90)
			(size 0.519938 1.4986)
			(layers "F.Cu" "F.Mask" "F.Paste")
			(net "M_C_CPU0_SA_DQ<11>")
		)
		(pad "166" smd rect
			(at 2.050034 -45.47489 90)
			(size 0.519938 1.4986)
			(layers "F.Cu" "F.Mask" "F.Paste")
			(net "GND")
		)
		(pad "167" smd rect
			(at 2.050034 -44.625006 90)
			(size 0.519938 1.4986)
			(layers "F.Cu" "F.Mask" "F.Paste")
			(net "M_C_CPU0_SA_DQS_DN<6>")
		)
		(pad "168" smd rect
			(at 2.050034 -43.775122 90)
			(size 0.519938 1.4986)
			(layers "F.Cu" "F.Mask" "F.Paste")
			(net "M_C_CPU0_SA_DQS_DP<6>")
		)
		(pad "169" smd rect
			(at 2.050034 -42.924984 90)
			(size 0.519938 1.4986)
			(layers "F.Cu" "F.Mask" "F.Paste")
			(net "GND")
		)
		(pad "170" smd rect
			(at 2.050034 -42.0751 90)
			(size 0.519938 1.4986)
			(layers "F.Cu" "F.Mask" "F.Paste")
			(net "M_C_CPU0_SA_DQ<14>")
		)
		(pad "171" smd rect
			(at 2.050034 -41.224962 90)
			(size 0.519938 1.4986)
			(layers "F.Cu" "F.Mask" "F.Paste")
			(net "GND")
		)
		(pad "172" smd rect
			(at 2.050034 -40.375078 90)
			(size 0.519938 1.4986)
			(layers "F.Cu" "F.Mask" "F.Paste")
			(net "M_C_CPU0_SA_DQ<15>")
		)
		(pad "173" smd rect
			(at 2.050034 -39.52494 90)
			(size 0.519938 1.4986)
			(layers "F.Cu" "F.Mask" "F.Paste")
			(net "GND")
		)
		(pad "174" smd rect
			(at 2.050034 -38.675056 90)
			(size 0.519938 1.4986)
			(layers "F.Cu" "F.Mask" "F.Paste")
			(net "M_C_CPU0_SA_DQ<18>")
		)
		(pad "175" smd rect
			(at 2.050034 -37.824918 90)
			(size 0.519938 1.4986)
			(layers "F.Cu" "F.Mask" "F.Paste")
			(net "GND")
		)
		(pad "176" smd rect
			(at 2.050034 -36.975034 90)
			(size 0.519938 1.4986)
			(layers "F.Cu" "F.Mask" "F.Paste")
			(net "M_C_CPU0_SA_DQ<19>")
		)
		(pad "177" smd rect
			(at 2.050034 -36.124896 90)
			(size 0.519938 1.4986)
			(layers "F.Cu" "F.Mask" "F.Paste")
			(net "GND")
		)
		(pad "178" smd rect
			(at 2.050034 -35.275012 90)
			(size 0.519938 1.4986)
			(layers "F.Cu" "F.Mask" "F.Paste")
			(net "M_C_CPU0_SA_DQS_DN<7>")
		)
		(pad "179" smd rect
			(at 2.050034 -34.425128 90)
			(size 0.519938 1.4986)
			(layers "F.Cu" "F.Mask" "F.Paste")
			(net "M_C_CPU0_SA_DQS_DP<7>")
		)
		(pad "180" smd rect
			(at 2.050034 -33.57499 90)
			(size 0.519938 1.4986)
			(layers "F.Cu" "F.Mask" "F.Paste")
			(net "GND")
		)
		(pad "181" smd rect
			(at 2.050034 -32.725106 90)
			(size 0.519938 1.4986)
			(layers "F.Cu" "F.Mask" "F.Paste")
			(net "M_C_CPU0_SA_DQ<22>")
		)
		(pad "182" smd rect
			(at 2.050034 -31.874968 90)
			(size 0.519938 1.4986)
			(layers "F.Cu" "F.Mask" "F.Paste")
			(net "GND")
		)
		(pad "183" smd rect
			(at 2.050034 -31.025084 90)
			(size 0.519938 1.4986)
			(layers "F.Cu" "F.Mask" "F.Paste")
			(net "M_C_CPU0_SA_DQ<23>")
		)
		(pad "184" smd rect
			(at 2.050034 -30.174946 90)
			(size 0.519938 1.4986)
			(layers "F.Cu" "F.Mask" "F.Paste")
			(net "GND")
		)
	)
)
